# TIMECARD (Time Appliance Project (Time Card)) — schematic netlist excerpt (pin names and nets, part order shuffled) for the footprints in the layout excerpt that follows; sources: Cadence DE-HDL packaged netlist, KiCad conversion of R4006-B0001-02_R01.brd

R195  RESISTOR  33OHM 1%  pkg SMC_0402R_H016  page 10 : \1\ = FPGA_TDO ; \2\ = R_FPGA_TDO
R488  RESISTOR  10KOHM 1%  pkg SMC_0402R_H016  page 33 : \1\ = UNNAMED_525_CAPACITOR_I14_1 ; \2\ = SG

(kicad_pcb
	(version 20260206)
	(generator "pcbnew")
	(generator_version "10.0")
	(general
		(thickness 1.6)
		(legacy_teardrops no)
	)
	(paper "A4")
	(title_block
		(title "timecard-production-celestica-r4006 — R4006-B0001-02_R01.brd")
		(comment 1 "Time Appliance Project (Time Card) / footprints 1027-1028 of 1113")
	)
	(layers
		(0 "F.Cu" signal "TOP")
		(4 "In1.Cu" signal "L02_GND1")
		(6 "In2.Cu" signal "L03_SIG1")
		(8 "In3.Cu" signal "L04_GND2")
		(10 "In4.Cu" signal "L05_VCC1")
		(12 "In5.Cu" signal "L06_VCC2")
		(14 "In6.Cu" signal "L07_GND3")
		(16 "In7.Cu" signal "L08_SIG2")
		(18 "In8.Cu" signal "L09_GND4")
		(2 "B.Cu" signal "BOTTOM")
		(9 "F.Adhes" user "F.Adhesive")
		(11 "B.Adhes" user "B.Adhesive")
		(13 "F.Paste" user "Package Geometry/Pastemask Top")
		(15 "B.Paste" user "Package Geometry/Pastemask Bottom")
		(5 "F.SilkS" user "Ref Des/Silkscreen Top")
		(7 "B.SilkS" user "Ref Des/Silkscreen Bottom")
		(1 "F.Mask" user "Board Geometry/Soldermask Top")
		(3 "B.Mask" user "Board Geometry/Soldermask Bottom")
		(17 "Dwgs.User" user "User.Drawings")
		(19 "Cmts.User" user "User.Comments")
		(21 "Eco1.User" user "User.Eco1")
		(23 "Eco2.User" user "User.Eco2")
		(25 "Edge.Cuts" user "Board Geometry/Outline")
		(27 "Margin" user)
		(31 "F.CrtYd" user "Package Geometry/Place Bound Top")
		(29 "B.CrtYd" user "Package Geometry/Place Bound Bottom")
		(35 "F.Fab" user "Ref Des/Assembly Top")
		(33 "B.Fab" user "Ref Des/Assembly Bottom")
	)
	(footprint ""
		(layer "B.Cu")
		(at 124.587 -45.974)
		(property "Reference" "R195"
			(at 3.683 0.16637 0)
			(unlocked yes)
			(layer "B.SilkS")
			(effects
				(font
					(size 0.7874 0.5842)
					(thickness 0.1524)
				)
				(justify mirror)
			)
		)
		(property "Value" "VAL*"
			(at -0.02032 2.13233 0)
			(unlocked yes)
			(layer "B.Fab")
			(hide yes)
			(effects
				(font
					(size 0.7874 0.5842)
					(thickness 0.1524)
				)
				(justify mirror)
			)
		)
		(property "Tolerance" "TOL*"
			(at -0.044704 3.05435 0)
			(unlocked yes)
			(layer "Cmts.User")
			(hide yes)
			(effects
				(font
					(size 0.7874 0.5842)
					(thickness 0.1524)
				)
				(justify mirror)
			)
		)
		(property "User Part Number" "PARTNUM*"
			(at -0.02032 4.024884 0)
			(unlocked yes)
			(layer "Cmts.User")
			(hide yes)
			(effects
				(font
					(size 0.7874 0.5842)
					(thickness 0.1524)
				)
				(justify mirror)
			)
		)
		(property "Device Type" "RESISTOR-G155-133R0-01,33OHM,1%"
			(at -0.008382 1.210564 0)
			(unlocked yes)
			(layer "B.Fab")
			(hide yes)
			(effects
				(font
					(size 0.7874 0.5842)
					(thickness 0.1524)
				)
				(justify mirror)
			)
		)
		(duplicate_pad_numbers_are_jumpers no)
		(fp_line
			(start -1.143 -0.5588)
			(end 1.143 -0.5588)
			(stroke
				(width 0.1)
				(type default)
			)
			(layer "B.SilkS")
		)
		(fp_line
			(start -1.143 0.5588)
			(end -1.143 -0.5588)
			(stroke
				(width 0.1)
				(type default)
			)
			(layer "B.SilkS")
		)
		(fp_line
			(start 1.143 -0.5588)
			(end 1.143 0.5588)
			(stroke
				(width 0.1)
				(type default)
			)
			(layer "B.SilkS")
		)
		(fp_line
			(start 1.143 0.5588)
			(end -1.143 0.5588)
			(stroke
				(width 0.1)
				(type default)
			)
			(layer "B.SilkS")
		)
		(fp_rect
			(start -1.143 -0.5588)
			(end 1.143 0.5588)
			(stroke
				(width 0)
				(type default)
			)
			(fill no)
			(layer "B.CrtYd")
		)
		(fp_line
			(start -0.508 -0.3048)
			(end 0.508 -0.3048)
			(stroke
				(width 0.1)
				(type default)
			)
			(layer "B.Fab")
		)
		(fp_line
			(start -0.508 0.3048)
			(end -0.508 -0.3048)
			(stroke
				(width 0.1)
				(type default)
			)
			(layer "B.Fab")
		)
		(fp_line
			(start 0.508 -0.3048)
			(end 0.508 0.3048)
			(stroke
				(width 0.1)
				(type default)
			)
			(layer "B.Fab")
		)
		(fp_line
			(start 0.508 0.3048)
			(end -0.508 0.3048)
			(stroke
				(width 0.1)
				(type default)
			)
			(layer "B.Fab")
		)
		(pad "1" smd rect
			(at 0.5334 0 180)
			(size 0.7112 0.6096)
			(layers "B.Cu" "B.Mask" "B.Paste")
			(net "FPGA_TDO")
		)
		(pad "2" smd rect
			(at -0.5334 0 180)
			(size 0.7112 0.6096)
			(layers "B.Cu" "B.Mask" "B.Paste")
			(net "R_FPGA_TDO")
		)
		(zone
			(layer "B.Cu")
			(hatch none 0.5)
			(connect_pads
				(clearance 0)
			)
			(min_thickness 0.25)
			(keepout
				(tracks allowed)
				(vias not_allowed)
				(pads allowed)
				(copperpour not_allowed)
				(footprints allowed)
			)
			(placement
				(enabled no)
				(sheetname "")
			)
			(fill
				(thermal_gap 0.5)
				(thermal_bridge_width 0.5)
				(island_removal_mode 0)
			)
			(polygon
				(pts
					(xy 124.5108 -46.2788) (xy 124.5108 -45.6692) (xy 124.6632 -45.6692) (xy 124.6632 -46.2788)
				)
			)
		)
	)
	(footprint ""
		(layer "B.Cu")
		(at 47.879 -75.184 -90)
		(property "Reference" "R488"
			(at 0.381 -1.23063 270)
			(unlocked yes)
			(layer "B.SilkS")
			(effects
				(font
					(size 0.7874 0.5842)
					(thickness 0.1524)
				)
				(justify mirror)
			)
		)
		(property "Value" "VAL*"
			(at -0.02032 2.13233 270)
			(unlocked yes)
			(layer "B.Fab")
			(hide yes)
			(effects
				(font
					(size 0.7874 0.5842)
					(thickness 0.1524)
				)
				(justify mirror)
			)
		)
		(property "Tolerance" "TOL*"
			(at -0.044704 3.05435 270)
			(unlocked yes)
			(layer "Cmts.User")
			(hide yes)
			(effects
				(font
					(size 0.7874 0.5842)
					(thickness 0.1524)
				)
				(justify mirror)
			)
		)
		(property "User Part Number" "PARTNUM*"
			(at -0.02032 4.024884 270)
			(unlocked yes)
			(layer "Cmts.User")
			(hide yes)
			(effects
				(font
					(size 0.7874 0.5842)
					(thickness 0.1524)
				)
				(justify mirror)
			)
		)
		(property "Device Type" "RESISTOR-G155-11002-01,10KOHM,A"
			(at -0.008382 1.210564 270)
			(unlocked yes)
			(layer "B.Fab")
			(hide yes)
			(effects
				(font
					(size 0.7874 0.5842)
					(thickness 0.1524)
				)
				(justify mirror)
			)
		)
		(duplicate_pad_numbers_are_jumpers no)
		(fp_line
			(start -1.143 0.5588)
			(end -1.143 -0.5588)
			(stroke
				(width 0.1)
				(type default)
			)
			(layer "B.SilkS")
		)
		(fp_line
			(start 1.143 0.5588)
			(end -1.143 0.5588)
			(stroke
				(width 0.1)
				(type default)
			)
			(layer "B.SilkS")
		)
		(fp_line
			(start -1.143 -0.5588)
			(end 1.143 -0.5588)
			(stroke
				(width 0.1)
				(type default)
			)
			(layer "B.SilkS")
		)
		(fp_line
			(start 1.143 -0.5588)
			(end 1.143 0.5588)
			(stroke
				(width 0.1)
				(type default)
			)
			(layer "B.SilkS")
		)
		(fp_poly
			(pts
				(xy 1.143 0.5588) (xy -1.143 0.5588) (xy -1.143 -0.5588) (xy 1.143 -0.5588)
			)
			(stroke
				(width 0)
				(type default)
			)
			(fill no)
			(layer "B.CrtYd")
		)
		(fp_line
			(start -0.508 0.3048)
			(end -0.508 -0.3048)
			(stroke
				(width 0.1)
				(type default)
			)
			(layer "B.Fab")
		)
		(fp_line
			(start 0.508 0.3048)
			(end -0.508 0.3048)
			(stroke
				(width 0.1)
				(type default)
			)
			(layer "B.Fab")
		)
		(fp_line
			(start -0.508 -0.3048)
			(end 0.508 -0.3048)
			(stroke
				(width 0.1)
				(type default)
			)
			(layer "B.Fab")
		)
		(fp_line
			(start 0.508 -0.3048)
			(end 0.508 0.3048)
			(stroke
				(width 0.1)
				(type default)
			)
			(layer "B.Fab")
		)
		(pad "1" smd rect
			(at 0.5334 0 90)
			(size 0.7112 0.6096)
			(layers "B.Cu" "B.Mask" "B.Paste")
			(net "UNNAMED_525_CAPACITOR_I14_1")
		)
		(pad "2" smd rect
			(at -0.5334 0 90)
			(size 0.7112 0.6096)
			(layers "B.Cu" "B.Mask" "B.Paste")
			(net "SG")
		)
		(zone
			(layer "B.Cu")
			(hatch none 0.5)
			(connect_pads
				(clearance 0)
			)
			(min_thickness 0.25)
			(keepout
				(tracks allowed)
				(vias not_allowed)
				(pads allowed)
				(copperpour not_allowed)
				(footprints allowed)
			)
			(placement
				(enabled no)
				(sheetname "")
			)
			(fill
				(thermal_gap 0.5)
				(thermal_bridge_width 0.5)
				(island_removal_mode 0)
			)
			(polygon
				(pts
					(xy 47.5742 -75.1078) (xy 48.1838 -75.1078) (xy 48.1838 -75.2602) (xy 47.5742 -75.2602)
				)
			)
		)
		(zone
			(layer "B.Cu")
			(hatch none 0.5)
			(connect_pads
				(clearance 0)
			)
			(min_thickness 0.25)
			(keepout
				(tracks not_allowed)
				(vias allowed)
				(pads allowed)
				(copperpour not_allowed)
				(footprints allowed)
			)
			(placement
				(enabled no)
				(sheetname "")
			)
			(fill
				(thermal_gap 0.5)
				(thermal_bridge_width 0.5)
				(island_removal_mode 0)
			)
			(polygon
				(pts
					(xy 47.5742 -75.1078) (xy 48.1838 -75.1078) (xy 48.1838 -75.2602) (xy 47.5742 -75.2602)
				)
			)
		)
	)
)
